#ISCELL
  pure_quanta quanta_title_block_c *
  *
#ISCELL
  standard offpage *
  page50_i19
#ISCELL
  standard offpage *
  page50_i20
#ISCELL
  standard offpage *
  page50_i21
#ISCELL
  standard offpage *
  page50_i22
#CELL
  pure_quanta socket4677_azif0045p001c01cs *
  page50_i23
